(kicad_pcb
	(version 20260206)
	(generator "pcbnew")
	(generator_version "10.0")
	(general
		(thickness 1.6)
		(legacy_teardrops no)
	)
	(paper "A4")
	(title_block
		(title "01162023_DA0F0TEBIF0_F0T_Expander_BD_F_brd_V02_OCP.brd")
		(comment 1 "Grand Teton / footprints 430-437 of 9728")
	)
	(layers
		(0 "F.Cu" signal "TOP")
		(4 "In1.Cu" signal "GND")
		(6 "In2.Cu" signal "VCC")
		(8 "In3.Cu" signal "VCC1")
		(10 "In4.Cu" signal "GND1")
		(12 "In5.Cu" signal "IN1")
		(14 "In6.Cu" signal "GND2")
		(16 "In7.Cu" signal "IN2")
		(18 "In8.Cu" signal "GND3")
		(20 "In9.Cu" signal "IN3")
		(22 "In10.Cu" signal "GND4")
		(24 "In11.Cu" signal "IN4")
		(26 "In12.Cu" signal "GND5")
		(28 "In13.Cu" signal "IN5")
		(30 "In14.Cu" signal "GND6")
		(32 "In15.Cu" signal "IN6")
		(34 "In16.Cu" signal "GND7")
		(2 "B.Cu" signal "BOTTOM")
		(9 "F.Adhes" user "F.Adhesive")
		(11 "B.Adhes" user "B.Adhesive")
		(13 "F.Paste" user "Package Geometry/Pastemask Top")
		(15 "B.Paste" user "Package Geometry/Pastemask Bottom")
		(5 "F.SilkS" user "Ref Des/Silkscreen Top")
		(7 "B.SilkS" user "Ref Des/Silkscreen Bottom")
		(1 "F.Mask" user "Board Geometry/Soldermask Top")
		(3 "B.Mask" user "Board Geometry/Soldermask Bottom")
		(17 "Dwgs.User" user "User.Drawings")
		(19 "Cmts.User" user "User.Comments")
		(21 "Eco1.User" user "User.Eco1")
		(23 "Eco2.User" user "User.Eco2")
		(25 "Edge.Cuts" user "Board Geometry/Outline")
		(27 "Margin" user)
		(31 "F.CrtYd" user "Package Geometry/Place Bound Top")
		(29 "B.CrtYd" user "Package Geometry/Place Bound Bottom")
		(35 "F.Fab" user "Ref Des/Assembly Top")
		(33 "B.Fab" user "Ref Des/Assembly Bottom")
	)
	(footprint ""
		(layer "F.Cu")
		(at 11.732768 -162.003994 90)
		(property "Reference" "PC615"
			(at 0 0 90)
			(layer "F.SilkS")
			(hide yes)
			(effects
				(font
					(size 1.27 1.27)
				)
			)
		)
		(property "Value" ""
			(at 0 0 90)
			(layer "F.Fab")
			(effects
				(font
					(size 1.27 1.27)
				)
			)
		)
		(duplicate_pad_numbers_are_jumpers no)
		(fp_line
			(start 0.7874 -0.4064)
			(end 0.7874 0.4064)
			(stroke
				(width 0.1524)
				(type default)
			)
			(layer "F.SilkS")
		)
		(fp_line
			(start -0.7874 -0.4064)
			(end 0.7874 -0.4064)
			(stroke
				(width 0.1524)
				(type default)
			)
			(layer "F.SilkS")
		)
		(fp_line
			(start 0.7874 0.4064)
			(end -0.7874 0.4064)
			(stroke
				(width 0.1524)
				(type default)
			)
			(layer "F.SilkS")
		)
		(fp_line
			(start -0.7874 0.4064)
			(end -0.7874 -0.4064)
			(stroke
				(width 0.1524)
				(type default)
			)
			(layer "F.SilkS")
		)
		(fp_line
			(start -0.12065 -0.305054)
			(end -0.12065 -0.2794)
			(stroke
				(width 0.1)
				(type default)
			)
			(layer "F.Fab")
		)
		(fp_line
			(start -0.67945 -0.305054)
			(end -0.12065 -0.305054)
			(stroke
				(width 0.1)
				(type default)
			)
			(layer "F.Fab")
		)
		(fp_line
			(start 0.67945 -0.3048)
			(end 0.67945 0.3048)
			(stroke
				(width 0.1)
				(type default)
			)
			(layer "F.Fab")
		)
		(fp_line
			(start 0.12065 -0.3048)
			(end 0.67945 -0.3048)
			(stroke
				(width 0.1)
				(type default)
			)
			(layer "F.Fab")
		)
		(fp_line
			(start 0.12065 -0.2794)
			(end 0.12065 -0.3048)
			(stroke
				(width 0.1)
				(type default)
			)
			(layer "F.Fab")
		)
		(fp_line
			(start -0.12065 -0.2794)
			(end 0.12065 -0.2794)
			(stroke
				(width 0.1)
				(type default)
			)
			(layer "F.Fab")
		)
		(fp_line
			(start 0.120396 0.2794)
			(end -0.12065 0.2794)
			(stroke
				(width 0.1)
				(type default)
			)
			(layer "F.Fab")
		)
		(fp_line
			(start -0.12065 0.2794)
			(end -0.12065 0.3048)
			(stroke
				(width 0.1)
				(type default)
			)
			(layer "F.Fab")
		)
		(fp_line
			(start 0.67945 0.3048)
			(end 0.120396 0.3048)
			(stroke
				(width 0.1)
				(type default)
			)
			(layer "F.Fab")
		)
		(fp_line
			(start 0.120396 0.3048)
			(end 0.120396 0.2794)
			(stroke
				(width 0.1)
				(type default)
			)
			(layer "F.Fab")
		)
		(fp_line
			(start -0.12065 0.3048)
			(end -0.67945 0.3048)
			(stroke
				(width 0.1)
				(type default)
			)
			(layer "F.Fab")
		)
		(fp_line
			(start -0.67945 0.3048)
			(end -0.67945 -0.305054)
			(stroke
				(width 0.1)
				(type default)
			)
			(layer "F.Fab")
		)
		(pad "1" smd circle
			(at -0.40005 0 90)
			(size 0 0)
			(layers "F.Cu" "F.Mask" "F.Paste")
			(net "P12V_NIC0_CO_ISET_R")
		)
		(pad "2" smd circle
			(at 0.40005 0 90)
			(size 0 0)
			(layers "F.Cu" "F.Mask" "F.Paste")
			(net "GND")
		)
	)
	(footprint ""
		(layer "F.Cu")
		(at 118.969028 -356.244906 90)
		(property "Reference" "C347"
			(at 0 0 90)
			(layer "F.SilkS")
			(hide yes)
			(effects
				(font
					(size 1.27 1.27)
				)
			)
		)
		(property "Value" ""
			(at 0 0 90)
			(layer "F.Fab")
			(effects
				(font
					(size 1.27 1.27)
				)
			)
		)
		(duplicate_pad_numbers_are_jumpers no)
		(fp_line
			(start 0.299974 -0.150114)
			(end 0.299974 0.150114)
			(stroke
				(width 0.1)
				(type default)
			)
			(layer "F.Fab")
		)
		(fp_line
			(start -0.299974 -0.150114)
			(end 0.299974 -0.150114)
			(stroke
				(width 0.1)
				(type default)
			)
			(layer "F.Fab")
		)
		(fp_line
			(start 0.299974 0.150114)
			(end -0.299974 0.150114)
			(stroke
				(width 0.1)
				(type default)
			)
			(layer "F.Fab")
		)
		(fp_line
			(start -0.299974 0.150114)
			(end -0.299974 -0.150114)
			(stroke
				(width 0.1)
				(type default)
			)
			(layer "F.Fab")
		)
		(pad "1" smd rect
			(at -0.2667 0 90)
			(size 0.3048 0.381)
			(layers "F.Cu" "F.Mask" "F.Paste")
			(net "P5E_PEX1_STN6_TX_DN<108>")
		)
		(pad "2" smd rect
			(at 0.2667 0 90)
			(size 0.3048 0.381)
			(layers "F.Cu" "F.Mask" "F.Paste")
			(net "P5E_PEX1_STN6_TX_C_DN<108>")
		)
	)
	(footprint ""
		(layer "F.Cu")
		(at 89.713308 -104.267508 -90)
		(property "Reference" "R701"
			(at 0 0 270)
			(layer "F.SilkS")
			(hide yes)
			(effects
				(font
					(size 1.27 1.27)
				)
			)
		)
		(property "Value" ""
			(at 0 0 270)
			(layer "F.Fab")
			(effects
				(font
					(size 1.27 1.27)
				)
			)
		)
		(duplicate_pad_numbers_are_jumpers no)
		(fp_line
			(start -0.7874 0.4064)
			(end -0.7874 -0.4064)
			(stroke
				(width 0.1524)
				(type default)
			)
			(layer "F.SilkS")
		)
		(fp_line
			(start 0.7874 0.4064)
			(end -0.7874 0.4064)
			(stroke
				(width 0.1524)
				(type default)
			)
			(layer "F.SilkS")
		)
		(fp_line
			(start -0.7874 -0.4064)
			(end 0.7874 -0.4064)
			(stroke
				(width 0.1524)
				(type default)
			)
			(layer "F.SilkS")
		)
		(fp_line
			(start 0.7874 -0.4064)
			(end 0.7874 0.4064)
			(stroke
				(width 0.1524)
				(type default)
			)
			(layer "F.SilkS")
		)
		(fp_line
			(start -0.67945 0.3048)
			(end -0.67945 -0.305054)
			(stroke
				(width 0.1)
				(type default)
			)
			(layer "F.Fab")
		)
		(fp_line
			(start -0.12065 0.3048)
			(end -0.67945 0.3048)
			(stroke
				(width 0.1)
				(type default)
			)
			(layer "F.Fab")
		)
		(fp_line
			(start 0.120396 0.3048)
			(end 0.120396 0.2794)
			(stroke
				(width 0.1)
				(type default)
			)
			(layer "F.Fab")
		)
		(fp_line
			(start 0.67945 0.3048)
			(end 0.120396 0.3048)
			(stroke
				(width 0.1)
				(type default)
			)
			(layer "F.Fab")
		)
		(fp_line
			(start -0.12065 0.2794)
			(end -0.12065 0.3048)
			(stroke
				(width 0.1)
				(type default)
			)
			(layer "F.Fab")
		)
		(fp_line
			(start 0.120396 0.2794)
			(end -0.12065 0.2794)
			(stroke
				(width 0.1)
				(type default)
			)
			(layer "F.Fab")
		)
		(fp_line
			(start -0.12065 -0.2794)
			(end 0.12065 -0.2794)
			(stroke
				(width 0.1)
				(type default)
			)
			(layer "F.Fab")
		)
		(fp_line
			(start 0.12065 -0.2794)
			(end 0.12065 -0.3048)
			(stroke
				(width 0.1)
				(type default)
			)
			(layer "F.Fab")
		)
		(fp_line
			(start 0.12065 -0.3048)
			(end 0.67945 -0.3048)
			(stroke
				(width 0.1)
				(type default)
			)
			(layer "F.Fab")
		)
		(fp_line
			(start 0.67945 -0.3048)
			(end 0.67945 0.3048)
			(stroke
				(width 0.1)
				(type default)
			)
			(layer "F.Fab")
		)
		(fp_line
			(start -0.67945 -0.305054)
			(end -0.12065 -0.305054)
			(stroke
				(width 0.1)
				(type default)
			)
			(layer "F.Fab")
		)
		(fp_line
			(start -0.12065 -0.305054)
			(end -0.12065 -0.2794)
			(stroke
				(width 0.1)
				(type default)
			)
			(layer "F.Fab")
		)
		(pad "1" smd circle
			(at -0.40005 0 270)
			(size 0 0)
			(layers "F.Cu" "F.Mask" "F.Paste")
			(net "P12V_NIC1")
		)
		(pad "2" smd circle
			(at 0.40005 0 270)
			(size 0 0)
			(layers "F.Cu" "F.Mask" "F.Paste")
			(net "P12V_NIC1_VIN_N")
		)
	)
	(footprint ""
		(layer "F.Cu")
		(at 378.453396 -300.992032)
		(property "Reference" "L137"
			(at 0 0 0)
			(layer "F.SilkS")
			(hide yes)
			(effects
				(font
					(size 1.27 1.27)
				)
			)
		)
		(property "Value" ""
			(at 0 0 0)
			(layer "F.Fab")
			(effects
				(font
					(size 1.27 1.27)
				)
			)
		)
		(duplicate_pad_numbers_are_jumpers no)
		(fp_line
			(start -1.63576 -0.8128)
			(end -1.63576 0.8128)
			(stroke
				(width 0.1524)
				(type default)
			)
			(layer "F.SilkS")
		)
		(fp_line
			(start -1.63576 -0.8128)
			(end 1.63576 -0.8128)
			(stroke
				(width 0.1524)
				(type default)
			)
			(layer "F.SilkS")
		)
		(fp_line
			(start 1.63576 -0.8128)
			(end 1.63576 0.8128)
			(stroke
				(width 0.1524)
				(type default)
			)
			(layer "F.SilkS")
		)
		(fp_line
			(start 1.63576 0.8128)
			(end -1.63576 0.8128)
			(stroke
				(width 0.1524)
				(type default)
			)
			(layer "F.SilkS")
		)
		(fp_line
			(start -1.56083 -0.738632)
			(end -1.56083 0.7366)
			(stroke
				(width 0.1)
				(type default)
			)
			(layer "F.Fab")
		)
		(fp_line
			(start -1.56083 0.7366)
			(end -1.524 0.7366)
			(stroke
				(width 0.1)
				(type default)
			)
			(layer "F.Fab")
		)
		(fp_line
			(start -1.524 0.7366)
			(end 1.524 0.7366)
			(stroke
				(width 0.1)
				(type default)
			)
			(layer "F.Fab")
		)
		(fp_line
			(start 1.524 0.7366)
			(end 1.560576 0.7366)
			(stroke
				(width 0.1)
				(type default)
			)
			(layer "F.Fab")
		)
		(fp_line
			(start 1.560576 -0.738632)
			(end -1.56083 -0.738632)
			(stroke
				(width 0.1)
				(type default)
			)
			(layer "F.Fab")
		)
		(fp_line
			(start 1.560576 0.7366)
			(end 1.560576 -0.738632)
			(stroke
				(width 0.1)
				(type default)
			)
			(layer "F.Fab")
		)
		(pad "1" smd rect
			(at -0.94996 0 180)
			(size 1.1176 1.3716)
			(layers "F.Cu" "F.Mask" "F.Paste")
			(net "P1V8_PLL0_PEX3")
		)
		(pad "2" smd rect
			(at 0.94996 0 180)
			(size 1.1176 1.3716)
			(layers "F.Cu" "F.Mask" "F.Paste")
			(net "PCEPLL1_VDDA18_PEX3")
		)
	)
	(footprint ""
		(layer "F.Cu")
		(at 404.18004 -142.9512)
		(property "Reference" "R315"
			(at 0 0 0)
			(layer "F.SilkS")
			(hide yes)
			(effects
				(font
					(size 1.27 1.27)
				)
			)
		)
		(property "Value" ""
			(at 0 0 0)
			(layer "F.Fab")
			(effects
				(font
					(size 1.27 1.27)
				)
			)
		)
		(duplicate_pad_numbers_are_jumpers no)
		(fp_line
			(start -0.7874 -0.4064)
			(end 0.7874 -0.4064)
			(stroke
				(width 0.1524)
				(type default)
			)
			(layer "F.SilkS")
		)
		(fp_line
			(start -0.7874 0.4064)
			(end -0.7874 -0.4064)
			(stroke
				(width 0.1524)
				(type default)
			)
			(layer "F.SilkS")
		)
		(fp_line
			(start 0.7874 -0.4064)
			(end 0.7874 0.4064)
			(stroke
				(width 0.1524)
				(type default)
			)
			(layer "F.SilkS")
		)
		(fp_line
			(start 0.7874 0.4064)
			(end -0.7874 0.4064)
			(stroke
				(width 0.1524)
				(type default)
			)
			(layer "F.SilkS")
		)
		(fp_line
			(start -0.67945 -0.305054)
			(end -0.12065 -0.305054)
			(stroke
				(width 0.1)
				(type default)
			)
			(layer "F.Fab")
		)
		(fp_line
			(start -0.67945 0.3048)
			(end -0.67945 -0.305054)
			(stroke
				(width 0.1)
				(type default)
			)
			(layer "F.Fab")
		)
		(fp_line
			(start -0.12065 -0.305054)
			(end -0.12065 -0.2794)
			(stroke
				(width 0.1)
				(type default)
			)
			(layer "F.Fab")
		)
		(fp_line
			(start -0.12065 -0.2794)
			(end 0.12065 -0.2794)
			(stroke
				(width 0.1)
				(type default)
			)
			(layer "F.Fab")
		)
		(fp_line
			(start -0.12065 0.2794)
			(end -0.12065 0.3048)
			(stroke
				(width 0.1)
				(type default)
			)
			(layer "F.Fab")
		)
		(fp_line
			(start -0.12065 0.3048)
			(end -0.67945 0.3048)
			(stroke
				(width 0.1)
				(type default)
			)
			(layer "F.Fab")
		)
		(fp_line
			(start 0.120396 0.2794)
			(end -0.12065 0.2794)
			(stroke
				(width 0.1)
				(type default)
			)
			(layer "F.Fab")
		)
		(fp_line
			(start 0.120396 0.3048)
			(end 0.120396 0.2794)
			(stroke
				(width 0.1)
				(type default)
			)
			(layer "F.Fab")
		)
		(fp_line
			(start 0.12065 -0.3048)
			(end 0.67945 -0.3048)
			(stroke
				(width 0.1)
				(type default)
			)
			(layer "F.Fab")
		)
		(fp_line
			(start 0.12065 -0.2794)
			(end 0.12065 -0.3048)
			(stroke
				(width 0.1)
				(type default)
			)
			(layer "F.Fab")
		)
		(fp_line
			(start 0.67945 -0.3048)
			(end 0.67945 0.3048)
			(stroke
				(width 0.1)
				(type default)
			)
			(layer "F.Fab")
		)
		(fp_line
			(start 0.67945 0.3048)
			(end 0.120396 0.3048)
			(stroke
				(width 0.1)
				(type default)
			)
			(layer "F.Fab")
		)
		(pad "1" smd circle
			(at -0.40005 0)
			(size 0 0)
			(layers "F.Cu" "F.Mask" "F.Paste")
			(net "SMB_NIC6_LS_SCL")
		)
		(pad "2" smd circle
			(at 0.40005 0)
			(size 0 0)
			(layers "F.Cu" "F.Mask" "F.Paste")
			(net "P3V3_NIC6")
		)
	)
	(footprint ""
		(layer "F.Cu")
		(at 461.600042 -407.599896)
		(property "Reference" "H61"
			(at -4.831842 -5.20573 0)
			(unlocked yes)
			(layer "F.SilkS")
			(effects
				(font
					(size 0.7874 0.5842)
					(thickness 0.1524)
				)
				(justify left)
			)
		)
		(property "Value" ""
			(at 0 0 0)
			(layer "F.Fab")
			(effects
				(font
					(size 1.27 1.27)
				)
			)
		)
		(duplicate_pad_numbers_are_jumpers no)
		(pad "1" thru_hole circle
			(at 0 0)
			(size 10.0076 10.0076)
			(drill 5.6134)
			(layers "*.Cu" "*.Mask")
			(remove_unused_layers no)
			(net "GND")
			(clearance -1.9431)
		)
	)
	(footprint ""
		(layer "F.Cu")
		(at 146.538442 -250.070874 -90)
		(property "Reference" "R1269"
			(at 0 0 270)
			(layer "F.SilkS")
			(hide yes)
			(effects
				(font
					(size 1.27 1.27)
				)
			)
		)
		(property "Value" ""
			(at 0 0 270)
			(layer "F.Fab")
			(effects
				(font
					(size 1.27 1.27)
				)
			)
		)
		(duplicate_pad_numbers_are_jumpers no)
		(fp_line
			(start -0.7874 0.4064)
			(end -0.7874 -0.4064)
			(stroke
				(width 0.1524)
				(type default)
			)
			(layer "F.SilkS")
		)
		(fp_line
			(start 0.7874 0.4064)
			(end -0.7874 0.4064)
			(stroke
				(width 0.1524)
				(type default)
			)
			(layer "F.SilkS")
		)
		(fp_line
			(start -0.7874 -0.4064)
			(end 0.7874 -0.4064)
			(stroke
				(width 0.1524)
				(type default)
			)
			(layer "F.SilkS")
		)
		(fp_line
			(start 0.7874 -0.4064)
			(end 0.7874 0.4064)
			(stroke
				(width 0.1524)
				(type default)
			)
			(layer "F.SilkS")
		)
		(fp_line
			(start -0.67945 0.3048)
			(end -0.67945 -0.305054)
			(stroke
				(width 0.1)
				(type default)
			)
			(layer "F.Fab")
		)
		(fp_line
			(start -0.12065 0.3048)
			(end -0.67945 0.3048)
			(stroke
				(width 0.1)
				(type default)
			)
			(layer "F.Fab")
		)
		(fp_line
			(start 0.120396 0.3048)
			(end 0.120396 0.2794)
			(stroke
				(width 0.1)
				(type default)
			)
			(layer "F.Fab")
		)
		(fp_line
			(start 0.67945 0.3048)
			(end 0.120396 0.3048)
			(stroke
				(width 0.1)
				(type default)
			)
			(layer "F.Fab")
		)
		(fp_line
			(start -0.12065 0.2794)
			(end -0.12065 0.3048)
			(stroke
				(width 0.1)
				(type default)
			)
			(layer "F.Fab")
		)
		(fp_line
			(start 0.120396 0.2794)
			(end -0.12065 0.2794)
			(stroke
				(width 0.1)
				(type default)
			)
			(layer "F.Fab")
		)
		(fp_line
			(start -0.12065 -0.2794)
			(end 0.12065 -0.2794)
			(stroke
				(width 0.1)
				(type default)
			)
			(layer "F.Fab")
		)
		(fp_line
			(start 0.12065 -0.2794)
			(end 0.12065 -0.3048)
			(stroke
				(width 0.1)
				(type default)
			)
			(layer "F.Fab")
		)
		(fp_line
			(start 0.12065 -0.3048)
			(end 0.67945 -0.3048)
			(stroke
				(width 0.1)
				(type default)
			)
			(layer "F.Fab")
		)
		(fp_line
			(start 0.67945 -0.3048)
			(end 0.67945 0.3048)
			(stroke
				(width 0.1)
				(type default)
			)
			(layer "F.Fab")
		)
		(fp_line
			(start -0.67945 -0.305054)
			(end -0.12065 -0.305054)
			(stroke
				(width 0.1)
				(type default)
			)
			(layer "F.Fab")
		)
		(fp_line
			(start -0.12065 -0.305054)
			(end -0.12065 -0.2794)
			(stroke
				(width 0.1)
				(type default)
			)
			(layer "F.Fab")
		)
		(pad "1" smd circle
			(at -0.40005 0 270)
			(size 0 0)
			(layers "F.Cu" "F.Mask" "F.Paste")
			(net "PEX1_MODE_SEL0")
		)
		(pad "2" smd circle
			(at 0.40005 0 270)
			(size 0 0)
			(layers "F.Cu" "F.Mask" "F.Paste")
			(net "P1V8_PEX")
		)
	)
	(footprint ""
		(layer "F.Cu")
		(at 410.637482 -190.246508 -90)
		(property "Reference" "R6440"
			(at 0 0 270)
			(layer "F.SilkS")
			(hide yes)
			(effects
				(font
					(size 1.27 1.27)
				)
			)
		)
		(property "Value" ""
			(at 0 0 270)
			(layer "F.Fab")
			(effects
				(font
					(size 1.27 1.27)
				)
			)
		)
		(duplicate_pad_numbers_are_jumpers no)
		(fp_line
			(start -0.7874 0.4064)
			(end -0.7874 -0.4064)
			(stroke
				(width 0.1524)
				(type default)
			)
			(layer "F.SilkS")
		)
		(fp_line
			(start 0.7874 0.4064)
			(end -0.7874 0.4064)
			(stroke
				(width 0.1524)
				(type default)
			)
			(layer "F.SilkS")
		)
		(fp_line
			(start -0.7874 -0.4064)
			(end 0.7874 -0.4064)
			(stroke
				(width 0.1524)
				(type default)
			)
			(layer "F.SilkS")
		)
		(fp_line
			(start 0.7874 -0.4064)
			(end 0.7874 0.4064)
			(stroke
				(width 0.1524)
				(type default)
			)
			(layer "F.SilkS")
		)
		(fp_line
			(start -0.67945 0.3048)
			(end -0.67945 -0.305054)
			(stroke
				(width 0.1)
				(type default)
			)
			(layer "F.Fab")
		)
		(fp_line
			(start -0.12065 0.3048)
			(end -0.67945 0.3048)
			(stroke
				(width 0.1)
				(type default)
			)
			(layer "F.Fab")
		)
		(fp_line
			(start 0.120396 0.3048)
			(end 0.120396 0.2794)
			(stroke
				(width 0.1)
				(type default)
			)
			(layer "F.Fab")
		)
		(fp_line
			(start 0.67945 0.3048)
			(end 0.120396 0.3048)
			(stroke
				(width 0.1)
				(type default)
			)
			(layer "F.Fab")
		)
		(fp_line
			(start -0.12065 0.2794)
			(end -0.12065 0.3048)
			(stroke
				(width 0.1)
				(type default)
			)
			(layer "F.Fab")
		)
		(fp_line
			(start 0.120396 0.2794)
			(end -0.12065 0.2794)
			(stroke
				(width 0.1)
				(type default)
			)
			(layer "F.Fab")
		)
		(fp_line
			(start -0.12065 -0.2794)
			(end 0.12065 -0.2794)
			(stroke
				(width 0.1)
				(type default)
			)
			(layer "F.Fab")
		)
		(fp_line
			(start 0.12065 -0.2794)
			(end 0.12065 -0.3048)
			(stroke
				(width 0.1)
				(type default)
			)
			(layer "F.Fab")
		)
		(fp_line
			(start 0.12065 -0.3048)
			(end 0.67945 -0.3048)
			(stroke
				(width 0.1)
				(type default)
			)
			(layer "F.Fab")
		)
		(fp_line
			(start 0.67945 -0.3048)
			(end 0.67945 0.3048)
			(stroke
				(width 0.1)
				(type default)
			)
			(layer "F.Fab")
		)
		(fp_line
			(start -0.67945 -0.305054)
			(end -0.12065 -0.305054)
			(stroke
				(width 0.1)
				(type default)
			)
			(layer "F.Fab")
		)
		(fp_line
			(start -0.12065 -0.305054)
			(end -0.12065 -0.2794)
			(stroke
				(width 0.1)
				(type default)
			)
			(layer "F.Fab")
		)
		(pad "1" smd circle
			(at -0.40005 0 270)
			(size 0 0)
			(layers "F.Cu" "F.Mask" "F.Paste")
			(net "FPGA_PEX2_MODE_SEL1_ISO")
		)
		(pad "2" smd circle
			(at 0.40005 0 270)
			(size 0 0)
			(layers "F.Cu" "F.Mask" "F.Paste")
			(net "PEX2_MODE_SEL1")
		)
	)
)
